(kicad_pcb
	(version 20221018)
	(generator pcbnew)
	(general
    (thickness 1.7403)
  )
	(paper "A4")
	(title_block
    (title "Data Center RDIMM DDR4 Tester")
    (date "2024-09-30")
    (rev "1.2.4")
		(comment 9 "footprints 458-466 of 690")
	)
	(layers
    (0 "F.Cu" signal)
    (1 "In1.Cu" power)
    (2 "In2.Cu" signal)
    (3 "In3.Cu" power)
    (4 "In4.Cu" power)
    (5 "In5.Cu" signal)
    (6 "In6.Cu" power)
    (7 "In7.Cu" signal)
    (8 "In8.Cu" power)
    (9 "In9.Cu" signal)
    (10 "In10.Cu" power)
    (31 "B.Cu" signal)
    (32 "B.Adhes" user "B.Adhesive")
    (33 "F.Adhes" user "F.Adhesive")
    (34 "B.Paste" user)
    (35 "F.Paste" user)
    (36 "B.SilkS" user "B.Silkscreen")
    (37 "F.SilkS" user "F.Silkscreen")
    (38 "B.Mask" user)
    (39 "F.Mask" user)
    (40 "Dwgs.User" user "User.Drawings")
    (41 "Cmts.User" user "User.Comments")
    (42 "Eco1.User" user "User.Eco1")
    (43 "Eco2.User" user "User.Eco2")
    (44 "Edge.Cuts" user)
    (45 "Margin" user)
    (46 "B.CrtYd" user "B.Courtyard")
    (47 "F.CrtYd" user "F.Courtyard")
    (48 "B.Fab" user)
    (49 "F.Fab" user)
  )
	(footprint "data-center-rdimm-ddr4-tester-footprints:C_0201" (layer "B.Cu")
    (at 181.186328 91.560008 -90)
    (descr "Capacitor SMD 0201")
    (tags "capacitor SMD 0201")
    (property "Author" "Antmicro")
    (property "Dielectric" "")
    (property "License" "Apache-2.0")
    (property "MPN" "CC0201KRX6S5BB104")
    (property "Manufacturer" "Yaego")
    (property "Sheetfile" "fpga-power.kicad_sch")
    (property "Sheetname" "FPGA power")
    (property "Val" "100n")
    (property "Voltage" "")
    (property "ki_description" " ")
    (attr smd)
    (fp_text reference "C64" (at -10.240008 -18.473672 90) (layer "B.SilkS")
        (effects (font (size 0.7 0.7) (thickness 0.15)) (justify left bottom mirror))
    )
    (fp_text value "C_100n_0201" (at 0 -1.4 90) (layer "B.Fab") hide
        (effects (font (size 0.7 0.7) (thickness 0.15)) (justify left bottom mirror))
    )
    (fp_text user "${REFERENCE}" (at -0.72 -3.4 90) (layer "B.Fab") hide
        (effects (font (size 0.7 0.7) (thickness 0.15)) (justify left bottom mirror))
    )
    (fp_text user "Author: Antmicro" (at -0.72 -5.4 90) (layer "B.Fab") hide
        (effects (font (size 0.7 0.7) (thickness 0.15)) (justify left bottom mirror))
    )
    (fp_text user "License: Apache-2.0" (at -0.72 -4.4 90) (layer "B.Fab") hide
        (effects (font (size 0.7 0.7) (thickness 0.15)) (justify left bottom mirror))
    )
    (fp_rect (start -0.72 0.38) (end 0.72 -0.38)
      (stroke (width 0.05) (type solid)) (fill none) (layer "B.CrtYd"))
    (fp_rect (start 0.3 -0.15) (end -0.301 0.149)
      (stroke (width 0.15) (type solid)) (fill none) (layer "B.Fab"))
    (pad "" smd roundrect (at -0.349 0.002 270) (size 0.318 0.36) (layers "B.Paste") (roundrect_rratio 0.25))
    (pad "" smd roundrect (at 0.341 0.002 270) (size 0.318 0.36) (layers "B.Paste") (roundrect_rratio 0.25))
    (pad "1" smd roundrect (at -0.321 0.002 270) (size 0.46 0.4) (layers "B.Cu" "B.Mask") (roundrect_rratio 0.25)
      (net 147 "1V0_SYS") (pintype "passive"))
    (pad "2" smd roundrect (at 0.32 0.002 270) (size 0.46 0.4) (layers "B.Cu" "B.Mask") (roundrect_rratio 0.25)
      (net 9 "GND") (pintype "passive"))
  )
	(footprint "data-center-rdimm-ddr4-tester-footprints:C_0201" (layer "B.Cu")
    (at 195.636328 78.010008 90)
    (descr "Capacitor SMD 0201")
    (tags "capacitor SMD 0201")
    (property "Author" "Antmicro")
    (property "Dielectric" "")
    (property "License" "Apache-2.0")
    (property "MPN" "CC0201KRX6S5BB104")
    (property "Manufacturer" "Yaego")
    (property "Sheetfile" "fpga-power.kicad_sch")
    (property "Sheetname" "FPGA power")
    (property "Val" "100n")
    (property "Voltage" "")
    (property "ki_description" " ")
    (attr smd)
    (fp_text reference "C34" (at 2.830008 0.333672 270) (layer "B.SilkS")
        (effects (font (size 0.7 0.7) (thickness 0.15)) (justify left bottom mirror))
    )
    (fp_text value "C_100n_0201" (at 0 -1.4 270) (layer "B.Fab") hide
        (effects (font (size 0.7 0.7) (thickness 0.15)) (justify left bottom mirror))
    )
    (fp_text user "Author: Antmicro" (at -0.72 -5.4 270) (layer "B.Fab") hide
        (effects (font (size 0.7 0.7) (thickness 0.15)) (justify left bottom mirror))
    )
    (fp_text user "${REFERENCE}" (at -0.72 -3.4 270) (layer "B.Fab") hide
        (effects (font (size 0.7 0.7) (thickness 0.15)) (justify left bottom mirror))
    )
    (fp_text user "License: Apache-2.0" (at -0.72 -4.4 270) (layer "B.Fab") hide
        (effects (font (size 0.7 0.7) (thickness 0.15)) (justify left bottom mirror))
    )
    (fp_rect (start -0.72 0.38) (end 0.72 -0.38)
      (stroke (width 0.05) (type solid)) (fill none) (layer "B.CrtYd"))
    (fp_rect (start 0.3 -0.15) (end -0.301 0.149)
      (stroke (width 0.15) (type solid)) (fill none) (layer "B.Fab"))
    (pad "" smd roundrect (at -0.349 0.002 90) (size 0.318 0.36) (layers "B.Paste") (roundrect_rratio 0.25))
    (pad "" smd roundrect (at 0.341 0.002 90) (size 0.318 0.36) (layers "B.Paste") (roundrect_rratio 0.25))
    (pad "1" smd roundrect (at -0.321 0.002 90) (size 0.46 0.4) (layers "B.Cu" "B.Mask") (roundrect_rratio 0.25)
      (net 77 "VDDQ") (pintype "passive"))
    (pad "2" smd roundrect (at 0.32 0.002 90) (size 0.46 0.4) (layers "B.Cu" "B.Mask") (roundrect_rratio 0.25)
      (net 9 "GND") (pintype "passive"))
  )
	(footprint "data-center-rdimm-ddr4-tester-footprints:C_0603_1608Metric" (layer "B.Cu")
    (at 174.936328 97.360008)
    (descr "Capacitor SMD 0603")
    (tags "capacitor 0603")
    (property "Author" "Antmicro")
    (property "Dielectric" "")
    (property "License" "Apache-2.0")
    (property "MPN" "GRM188R60J476ME15D")
    (property "Manufacturer" "Murata")
    (property "Sheetfile" "fpga-power.kicad_sch")
    (property "Sheetname" "FPGA power")
    (property "Val" "47u")
    (property "Voltage" "")
    (property "ki_description" " ")
    (attr smd)
    (fp_text reference "C3" (at 2.523672 0.489992 180) (layer "B.SilkS")
        (effects (font (size 0.7 0.7) (thickness 0.15)) (justify left bottom mirror))
    )
    (fp_text value "C_47u_0603" (at 0 -1.6 180) (layer "B.Fab") hide
        (effects (font (size 0.7 0.7) (thickness 0.15)) (justify left bottom mirror))
    )
    (fp_text user "${REFERENCE}" (at -1.682 -3.895 180) (layer "B.Fab") hide
        (effects (font (size 0.7 0.7) (thickness 0.15)) (justify left bottom mirror))
    )
    (fp_text user "Author: Antmicro" (at -1.682 -4.894 180) (layer "B.Fab") hide
        (effects (font (size 0.7 0.7) (thickness 0.15)) (justify left bottom mirror))
    )
    (fp_text user "License: Apache-2.0" (at -1.682 -5.895 180) (layer "B.Fab") hide
        (effects (font (size 0.7 0.7) (thickness 0.15)) (justify left bottom mirror))
    )
    (fp_line (start -0.3 -0.3) (end 0.3 -0.3)
      (stroke (width 0.15) (type solid)) (layer "B.SilkS"))
    (fp_line (start -0.3 0.3) (end 0.3 0.3)
      (stroke (width 0.15) (type solid)) (layer "B.SilkS"))
    (fp_rect (start -1.24 0.7) (end 1.24 -0.7)
      (stroke (width 0.05) (type solid)) (fill none) (layer "B.CrtYd"))
    (fp_rect (start -0.8 0.4) (end 0.8 -0.4)
      (stroke (width 0.15) (type solid)) (fill none) (layer "B.Fab"))
    (pad "1" smd roundrect (at -0.7 0) (size 0.6 0.8) (layers "B.Cu" "B.Paste" "B.Mask") (roundrect_rratio 0.2)
      (net 143 "3V3_SYS") (pintype "passive"))
    (pad "2" smd roundrect (at 0.7 0) (size 0.6 0.8) (layers "B.Cu" "B.Paste" "B.Mask") (roundrect_rratio 0.2)
      (net 9 "GND") (pintype "passive"))
  )
	(footprint "data-center-rdimm-ddr4-tester-footprints:C_0603_1608Metric" (layer "B.Cu")
    (at 176.825 83.7 90)
    (descr "Capacitor SMD 0603")
    (tags "capacitor 0603")
    (property "Author" "Antmicro")
    (property "Dielectric" "")
    (property "License" "Apache-2.0")
    (property "MPN" "GRM188R60J476ME15D")
    (property "Manufacturer" "Murata")
    (property "Sheetfile" "fpga-power.kicad_sch")
    (property "Sheetname" "FPGA power")
    (property "Val" "47u")
    (property "Voltage" "")
    (property "ki_description" " ")
    (attr smd)
    (fp_text reference "C6" (at 2.54 0.355 270) (layer "B.SilkS")
        (effects (font (size 0.7 0.7) (thickness 0.15)) (justify left bottom mirror))
    )
    (fp_text value "C_47u_0603" (at 0 -1.6 270) (layer "B.Fab") hide
        (effects (font (size 0.7 0.7) (thickness 0.15)) (justify left bottom mirror))
    )
    (fp_text user "License: Apache-2.0" (at -1.682 -5.895 270) (layer "B.Fab") hide
        (effects (font (size 0.7 0.7) (thickness 0.15)) (justify left bottom mirror))
    )
    (fp_text user "Author: Antmicro" (at -1.682 -4.894 270) (layer "B.Fab") hide
        (effects (font (size 0.7 0.7) (thickness 0.15)) (justify left bottom mirror))
    )
    (fp_text user "${REFERENCE}" (at -1.682 -3.895 270) (layer "B.Fab") hide
        (effects (font (size 0.7 0.7) (thickness 0.15)) (justify left bottom mirror))
    )
    (fp_line (start -0.3 -0.3) (end 0.3 -0.3)
      (stroke (width 0.15) (type solid)) (layer "B.SilkS"))
    (fp_line (start -0.3 0.3) (end 0.3 0.3)
      (stroke (width 0.15) (type solid)) (layer "B.SilkS"))
    (fp_rect (start -1.24 0.7) (end 1.24 -0.7)
      (stroke (width 0.05) (type solid)) (fill none) (layer "B.CrtYd"))
    (fp_rect (start -0.8 0.4) (end 0.8 -0.4)
      (stroke (width 0.15) (type solid)) (fill none) (layer "B.Fab"))
    (pad "1" smd roundrect (at -0.7 0 90) (size 0.6 0.8) (layers "B.Cu" "B.Paste" "B.Mask") (roundrect_rratio 0.2)
      (net 143 "3V3_SYS") (pintype "passive"))
    (pad "2" smd roundrect (at 0.7 0 90) (size 0.6 0.8) (layers "B.Cu" "B.Paste" "B.Mask") (roundrect_rratio 0.2)
      (net 9 "GND") (pintype "passive"))
  )
	(footprint "data-center-rdimm-ddr4-tester-footprints:C_0402_1005Metric" (layer "B.Cu")
    (at 185.086328 92.975008 -90)
    (descr "Capacitor SMD 0402")
    (tags "capacitor SMD 0402")
    (property "Author" "Antmicro")
    (property "Dielectric" "")
    (property "License" "Apache-2.0")
    (property "MPN" "GRM155R61A475MEAAD")
    (property "Manufacturer" "Murata")
    (property "Sheetfile" "fpga-power.kicad_sch")
    (property "Sheetname" "FPGA power")
    (property "Val" "4u7")
    (property "Voltage" "")
    (property "ki_description" " ")
    (attr smd)
    (fp_text reference "C7" (at -9.855008 -18.433672 90) (layer "B.SilkS")
        (effects (font (size 0.7 0.7) (thickness 0.15)) (justify left bottom mirror))
    )
    (fp_text value "C_4u7_0402" (at 0 -1.4 90) (layer "B.Fab") hide
        (effects (font (size 0.7 0.7) (thickness 0.15)) (justify left bottom mirror))
    )
    (fp_text user "${REFERENCE}" (at -0.932 -3.168 90) (layer "B.Fab") hide
        (effects (font (size 0.7 0.7) (thickness 0.15)) (justify left bottom mirror))
    )
    (fp_text user "License: Apache-2.0" (at -0.932 -5.17 90) (layer "B.Fab") hide
        (effects (font (size 0.7 0.7) (thickness 0.15)) (justify left bottom mirror))
    )
    (fp_text user "Author: Antmicro" (at -0.932 -4.17 90) (layer "B.Fab") hide
        (effects (font (size 0.7 0.7) (thickness 0.15)) (justify left bottom mirror))
    )
    (fp_rect (start -0.94 0.47) (end 0.94 -0.47)
      (stroke (width 0.05) (type solid)) (fill none) (layer "B.CrtYd"))
    (fp_rect (start -0.499 0.249) (end 0.499 -0.249)
      (stroke (width 0.15) (type solid)) (fill none) (layer "B.Fab"))
    (pad "1" smd roundrect (at -0.484 0 270) (size 0.59 0.64) (layers "B.Cu" "B.Paste" "B.Mask") (roundrect_rratio 0.25)
      (net 144 "1V8_SYS") (pintype "passive"))
    (pad "2" smd roundrect (at 0.484 0 270) (size 0.59 0.64) (layers "B.Cu" "B.Paste" "B.Mask") (roundrect_rratio 0.25)
      (net 9 "GND") (pintype "passive"))
  )
	(footprint "data-center-rdimm-ddr4-tester-footprints:C_0201" (layer "B.Cu")
    (at 186.95 87.45 180)
    (descr "Capacitor SMD 0201")
    (tags "capacitor SMD 0201")
    (property "Author" "Antmicro")
    (property "Dielectric" "")
    (property "License" "Apache-2.0")
    (property "MPN" "CC0201KRX6S5BB104")
    (property "Manufacturer" "Yaego")
    (property "Sheetfile" "fpga-power.kicad_sch")
    (property "Sheetname" "FPGA power")
    (property "Val" "100n")
    (property "Voltage" "")
    (property "ki_description" " ")
    (attr smd)
    (fp_text reference "C9" (at -18.58 9.37) (layer "B.SilkS")
        (effects (font (size 0.7 0.7) (thickness 0.15)) (justify left bottom mirror))
    )
    (fp_text value "C_100n_0201" (at 0 -1.4) (layer "B.Fab") hide
        (effects (font (size 0.7 0.7) (thickness 0.15)) (justify left bottom mirror))
    )
    (fp_text user "License: Apache-2.0" (at -0.72 -4.4) (layer "B.Fab") hide
        (effects (font (size 0.7 0.7) (thickness 0.15)) (justify left bottom mirror))
    )
    (fp_text user "Author: Antmicro" (at -0.72 -5.4) (layer "B.Fab") hide
        (effects (font (size 0.7 0.7) (thickness 0.15)) (justify left bottom mirror))
    )
    (fp_text user "${REFERENCE}" (at -0.72 -3.4) (layer "B.Fab") hide
        (effects (font (size 0.7 0.7) (thickness 0.15)) (justify left bottom mirror))
    )
    (fp_rect (start -0.72 0.38) (end 0.72 -0.38)
      (stroke (width 0.05) (type solid)) (fill none) (layer "B.CrtYd"))
    (fp_rect (start 0.3 -0.15) (end -0.301 0.149)
      (stroke (width 0.15) (type solid)) (fill none) (layer "B.Fab"))
    (pad "" smd roundrect (at -0.349 0.002 180) (size 0.318 0.36) (layers "B.Paste") (roundrect_rratio 0.25))
    (pad "" smd roundrect (at 0.341 0.002 180) (size 0.318 0.36) (layers "B.Paste") (roundrect_rratio 0.25))
    (pad "1" smd roundrect (at -0.321 0.002 180) (size 0.46 0.4) (layers "B.Cu" "B.Mask") (roundrect_rratio 0.25)
      (net 144 "1V8_SYS") (pintype "passive"))
    (pad "2" smd roundrect (at 0.32 0.002 180) (size 0.46 0.4) (layers "B.Cu" "B.Mask") (roundrect_rratio 0.25)
      (net 9 "GND") (pintype "passive"))
  )
	(footprint "data-center-rdimm-ddr4-tester-footprints:C_0201" (layer "B.Cu")
    (at 189.086328 89.560008 90)
    (descr "Capacitor SMD 0201")
    (tags "capacitor SMD 0201")
    (property "Author" "Antmicro")
    (property "Dielectric" "")
    (property "License" "Apache-2.0")
    (property "MPN" "CC0201KRX6S5BB104")
    (property "Manufacturer" "Yaego")
    (property "Sheetfile" "fpga-power.kicad_sch")
    (property "Sheetname" "FPGA power")
    (property "Val" "100n")
    (property "Voltage" "")
    (property "ki_description" " ")
    (attr smd)
    (fp_text reference "C11" (at 10.120008 18.163672 270) (layer "B.SilkS")
        (effects (font (size 0.7 0.7) (thickness 0.15)) (justify left bottom mirror))
    )
    (fp_text value "C_100n_0201" (at 0 -1.4 270) (layer "B.Fab") hide
        (effects (font (size 0.7 0.7) (thickness 0.15)) (justify left bottom mirror))
    )
    (fp_text user "License: Apache-2.0" (at -0.72 -4.4 270) (layer "B.Fab") hide
        (effects (font (size 0.7 0.7) (thickness 0.15)) (justify left bottom mirror))
    )
    (fp_text user "Author: Antmicro" (at -0.72 -5.4 270) (layer "B.Fab") hide
        (effects (font (size 0.7 0.7) (thickness 0.15)) (justify left bottom mirror))
    )
    (fp_text user "${REFERENCE}" (at -0.72 -3.4 270) (layer "B.Fab") hide
        (effects (font (size 0.7 0.7) (thickness 0.15)) (justify left bottom mirror))
    )
    (fp_rect (start -0.72 0.38) (end 0.72 -0.38)
      (stroke (width 0.05) (type solid)) (fill none) (layer "B.CrtYd"))
    (fp_rect (start 0.3 -0.15) (end -0.301 0.149)
      (stroke (width 0.15) (type solid)) (fill none) (layer "B.Fab"))
    (pad "" smd roundrect (at -0.349 0.002 90) (size 0.318 0.36) (layers "B.Paste") (roundrect_rratio 0.25))
    (pad "" smd roundrect (at 0.341 0.002 90) (size 0.318 0.36) (layers "B.Paste") (roundrect_rratio 0.25))
    (pad "1" smd roundrect (at -0.321 0.002 90) (size 0.46 0.4) (layers "B.Cu" "B.Mask") (roundrect_rratio 0.25)
      (net 144 "1V8_SYS") (pintype "passive"))
    (pad "2" smd roundrect (at 0.32 0.002 90) (size 0.46 0.4) (layers "B.Cu" "B.Mask") (roundrect_rratio 0.25)
      (net 9 "GND") (pintype "passive"))
  )
	(footprint "data-center-rdimm-ddr4-tester-footprints:C_0603_1608Metric" (layer "B.Cu")
    (at 184.936328 101.960008 180)
    (descr "Capacitor SMD 0603")
    (tags "capacitor 0603")
    (property "Author" "Antmicro")
    (property "Dielectric" "")
    (property "License" "Apache-2.0")
    (property "MPN" "GRM188R60J476ME15D")
    (property "Manufacturer" "Murata")
    (property "Sheetfile" "fpga-power.kicad_sch")
    (property "Sheetname" "FPGA power")
    (property "Val" "47u")
    (property "Voltage" "")
    (property "ki_description" " ")
    (attr smd)
    (fp_text reference "C15" (at 0.916328 -0.369992) (layer "B.SilkS")
        (effects (font (size 0.7 0.7) (thickness 0.15)) (justify left bottom mirror))
    )
    (fp_text value "C_47u_0603" (at 0 -1.6) (layer "B.Fab") hide
        (effects (font (size 0.7 0.7) (thickness 0.15)) (justify left bottom mirror))
    )
    (fp_text user "License: Apache-2.0" (at -1.682 -5.895) (layer "B.Fab") hide
        (effects (font (size 0.7 0.7) (thickness 0.15)) (justify left bottom mirror))
    )
    (fp_text user "${REFERENCE}" (at -1.682 -3.895) (layer "B.Fab") hide
        (effects (font (size 0.7 0.7) (thickness 0.15)) (justify left bottom mirror))
    )
    (fp_text user "Author: Antmicro" (at -1.682 -4.894) (layer "B.Fab") hide
        (effects (font (size 0.7 0.7) (thickness 0.15)) (justify left bottom mirror))
    )
    (fp_line (start -0.3 -0.3) (end 0.3 -0.3)
      (stroke (width 0.15) (type solid)) (layer "B.SilkS"))
    (fp_line (start -0.3 0.3) (end 0.3 0.3)
      (stroke (width 0.15) (type solid)) (layer "B.SilkS"))
    (fp_rect (start -1.24 0.7) (end 1.24 -0.7)
      (stroke (width 0.05) (type solid)) (fill none) (layer "B.CrtYd"))
    (fp_rect (start -0.8 0.4) (end 0.8 -0.4)
      (stroke (width 0.15) (type solid)) (fill none) (layer "B.Fab"))
    (pad "1" smd roundrect (at -0.7 0 180) (size 0.6 0.8) (layers "B.Cu" "B.Paste" "B.Mask") (roundrect_rratio 0.2)
      (net 143 "3V3_SYS") (pintype "passive"))
    (pad "2" smd roundrect (at 0.7 0 180) (size 0.6 0.8) (layers "B.Cu" "B.Paste" "B.Mask") (roundrect_rratio 0.2)
      (net 9 "GND") (pintype "passive"))
  )
	(footprint "data-center-rdimm-ddr4-tester-footprints:C_0402_1005Metric" (layer "B.Cu")
    (at 186.8 86.3)
    (descr "Capacitor SMD 0402")
    (tags "capacitor SMD 0402")
    (property "Author" "Antmicro")
    (property "Dielectric" "")
    (property "License" "Apache-2.0")
    (property "MPN" "GRM155R61A475MEAAD")
    (property "Manufacturer" "Murata")
    (property "Sheetfile" "fpga-power.kicad_sch")
    (property "Sheetname" "FPGA power")
    (property "Val" "4u7")
    (property "Voltage" "")
    (property "ki_description" " ")
    (attr smd)
    (fp_text reference "C16" (at 18.7 -9.13 180) (layer "B.SilkS")
        (effects (font (size 0.7 0.7) (thickness 0.15)) (justify left bottom mirror))
    )
    (fp_text value "C_4u7_0402" (at 0 -1.4 180) (layer "B.Fab") hide
        (effects (font (size 0.7 0.7) (thickness 0.15)) (justify left bottom mirror))
    )
    (fp_text user "Author: Antmicro" (at -0.932 -4.17 180) (layer "B.Fab") hide
        (effects (font (size 0.7 0.7) (thickness 0.15)) (justify left bottom mirror))
    )
    (fp_text user "${REFERENCE}" (at -0.932 -3.168 180) (layer "B.Fab") hide
        (effects (font (size 0.7 0.7) (thickness 0.15)) (justify left bottom mirror))
    )
    (fp_text user "License: Apache-2.0" (at -0.932 -5.17 180) (layer "B.Fab") hide
        (effects (font (size 0.7 0.7) (thickness 0.15)) (justify left bottom mirror))
    )
    (fp_rect (start -0.94 0.47) (end 0.94 -0.47)
      (stroke (width 0.05) (type solid)) (fill none) (layer "B.CrtYd"))
    (fp_rect (start -0.499 0.249) (end 0.499 -0.249)
      (stroke (width 0.15) (type solid)) (fill none) (layer "B.Fab"))
    (pad "1" smd roundrect (at -0.484 0) (size 0.59 0.64) (layers "B.Cu" "B.Paste" "B.Mask") (roundrect_rratio 0.25)
      (net 144 "1V8_SYS") (pintype "passive"))
    (pad "2" smd roundrect (at 0.484 0) (size 0.59 0.64) (layers "B.Cu" "B.Paste" "B.Mask") (roundrect_rratio 0.25)
      (net 9 "GND") (pintype "passive"))
  )
)
